(kicad_pcb
	(version 20241229)
	(generator "pcbnew")
	(generator_version "9.0")
	(general
		(thickness 1.552)
		(legacy_teardrops no)
	)
	(paper "A4")
	(title_block
		(date "2023-07-25")
		(rev "1.1.4")
		(comment 9 "footprints 378-379 of 379")
	)
	(layers
		(0 "F.Cu" signal)
		(4 "In1.Cu" signal)
		(6 "In2.Cu" signal)
		(8 "In3.Cu" signal)
		(10 "In4.Cu" signal)
		(12 "In5.Cu" signal)
		(14 "In6.Cu" signal)
		(2 "B.Cu" signal)
		(9 "F.Adhes" user "F.Adhesive")
		(11 "B.Adhes" user "B.Adhesive")
		(13 "F.Paste" user)
		(15 "B.Paste" user)
		(5 "F.SilkS" user "F.Silkscreen")
		(7 "B.SilkS" user "B.Silkscreen")
		(1 "F.Mask" user)
		(3 "B.Mask" user)
		(17 "Dwgs.User" user "User.Drawings")
		(19 "Cmts.User" user "User.Comments")
		(21 "Eco1.User" user "User.Eco1")
		(23 "Eco2.User" user "User.Eco2")
		(25 "Edge.Cuts" user)
		(27 "Margin" user)
		(31 "F.CrtYd" user "F.Courtyard")
		(29 "B.CrtYd" user "B.Courtyard")
		(35 "F.Fab" user)
		(33 "B.Fab" user)
	)
	(footprint "antmicro-footprints:FB_0603_1608Metric"
		(layer "B.Cu")
		(at 137.48 91.68)
		(property "Reference" "FB2"
			(at 1.05 1.46 180)
			(layer "B.SilkS")
			(effects
				(font
					(size 0.65 0.65)
					(thickness 0.15)
				)
				(justify left bottom mirror)
			)
		)
		(property "Value" "FB_120Z_2A_0603"
			(at 0 -1.5 180)
			(layer "B.Fab")
			(hide yes)
			(effects
				(font
					(size 0.7 0.7)
					(thickness 0.15)
				)
				(justify left bottom mirror)
			)
		)
		(property "Datasheet" "https://www.murata.com/en-us/products/productdata/8796738650142/ENFA0003.pdf"
			(at 0 0 0)
			(layer "F.Fab")
			(hide yes)
			(effects
				(font
					(size 1.27 1.27)
					(thickness 0.15)
				)
			)
		)
		(property "Description" "Ferrite Bead, 0603 [1608 Metric], 120 ohm, 2 A, BLM18P, 0.05 ohm, ± 25%, DC power line"
			(at 0 0 0)
			(layer "F.Fab")
			(hide yes)
			(effects
				(font
					(size 1.27 1.27)
					(thickness 0.15)
				)
			)
		)
		(property "Author" "Antmicro"
			(at 0 0 0)
			(layer "B.Fab")
			(hide yes)
			(effects
				(font
					(size 1 1)
					(thickness 0.15)
				)
				(justify mirror)
			)
		)
		(property "License" "Apache-2.0"
			(at 0 0 0)
			(layer "B.Fab")
			(hide yes)
			(effects
				(font
					(size 1 1)
					(thickness 0.15)
				)
				(justify mirror)
			)
		)
		(property "MPN" "BLM18PG121SN1D"
			(at 0 0 0)
			(layer "B.Fab")
			(hide yes)
			(effects
				(font
					(size 1 1)
					(thickness 0.15)
				)
				(justify mirror)
			)
		)
		(property "Manufacturer" "Murata"
			(at 0 0 0)
			(layer "B.Fab")
			(hide yes)
			(effects
				(font
					(size 1 1)
					(thickness 0.15)
				)
				(justify mirror)
			)
		)
		(property "Val" "120Z/2A"
			(at 0 0 0)
			(unlocked yes)
			(layer "B.Fab")
			(hide yes)
			(effects
				(font
					(size 1 1)
					(thickness 0.15)
				)
				(justify mirror)
			)
		)
		(property "Current" ""
			(at 0 0 0)
			(unlocked yes)
			(layer "B.Fab")
			(hide yes)
			(effects
				(font
					(size 1 1)
					(thickness 0.15)
				)
				(justify mirror)
			)
		)
		(sheetname "/FPGA Power/")
		(sheetfile "FPGA_Power.kicad_sch")
		(attr smd)
		(fp_line
			(start -0.15 -0.4)
			(end 0.15 -0.4)
			(stroke
				(width 0.15)
				(type solid)
			)
			(layer "B.SilkS")
		)
		(fp_line
			(start -0.15 0.4)
			(end 0.15 0.4)
			(stroke
				(width 0.15)
				(type solid)
			)
			(layer "B.SilkS")
		)
		(fp_rect
			(start -1.25 0.65)
			(end 1.25 -0.65)
			(stroke
				(width 0.05)
				(type solid)
			)
			(fill no)
			(layer "B.CrtYd")
		)
		(fp_line
			(start -0.803 -0.406)
			(end -0.803 0.408)
			(stroke
				(width 0.15)
				(type solid)
			)
			(layer "B.Fab")
		)
		(fp_line
			(start 0.8 -0.406)
			(end -0.803 -0.406)
			(stroke
				(width 0.15)
				(type solid)
			)
			(layer "B.Fab")
		)
		(fp_line
			(start 0.8 0.408)
			(end -0.803 0.408)
			(stroke
				(width 0.15)
				(type solid)
			)
			(layer "B.Fab")
		)
		(fp_line
			(start 0.8 0.408)
			(end 0.8 -0.406)
			(stroke
				(width 0.15)
				(type solid)
			)
			(layer "B.Fab")
		)
		(fp_text user "${REFERENCE}"
			(at -1.653 -4.6 180)
			(layer "B.Fab")
			(effects
				(font
					(size 0.7 0.7)
					(thickness 0.15)
				)
				(justify left bottom mirror)
			)
		)
		(fp_text user "License: Apache-2.0"
			(at -1.653 -5.9 180)
			(layer "B.Fab")
			(effects
				(font
					(size 0.7 0.7)
					(thickness 0.15)
				)
				(justify left bottom mirror)
			)
		)
		(fp_text user "Author: Antmicro"
			(at -1.653 -3.162 180)
			(layer "B.Fab")
			(effects
				(font
					(size 0.7 0.7)
					(thickness 0.15)
				)
				(justify left bottom mirror)
			)
		)
		(pad "1" smd roundrect
			(at -0.7 0)
			(size 0.8 1)
			(layers "B.Cu" "B.Mask" "B.Paste")
			(roundrect_rratio 0.2)
			(net 10 "/FPGA Power/VCC_AUXA")
			(pintype "passive")
		)
		(pad "2" smd roundrect
			(at 0.7 0)
			(size 0.8 1)
			(layers "B.Cu" "B.Mask" "B.Paste")
			(roundrect_rratio 0.2)
			(net 50 "+1V8")
			(pintype "passive")
		)
	)
	(footprint "antmicro-footprints:R_0402_1005Metric"
		(layer "B.Cu")
		(at 155.89 72.9 90)
		(descr "Resistor SMD 0402")
		(tags "resistor SMD 0402")
		(property "Reference" "R98"
			(at 0.96 -0.66 270)
			(layer "B.SilkS")
			(effects
				(font
					(size 0.65 0.65)
					(thickness 0.15)
				)
				(justify left bottom mirror)
			)
		)
		(property "Value" "R_10k_0402"
			(at 0 -1.4 270)
			(layer "B.Fab")
			(hide yes)
			(effects
				(font
					(size 0.7 0.7)
					(thickness 0.15)
				)
				(justify left bottom mirror)
			)
		)
		(property "Datasheet" "https://www.bourns.com/docs/product-datasheets/cr.pdf"
			(at 0 0 90)
			(layer "F.Fab")
			(hide yes)
			(effects
				(font
					(size 1.27 1.27)
					(thickness 0.15)
				)
			)
		)
		(property "Description" "SMD Chip Resistor, 10 kohm, ± 1%, 62.5 mW, 0402 [1005 Metric], Thick Film, General Purpose"
			(at 0 0 90)
			(layer "F.Fab")
			(hide yes)
			(effects
				(font
					(size 1.27 1.27)
					(thickness 0.15)
				)
			)
		)
		(property "Author" "Antmicro"
			(at 228.79 -82.99 0)
			(layer "B.Fab")
			(hide yes)
			(effects
				(font
					(size 1 1)
					(thickness 0.15)
				)
				(justify mirror)
			)
		)
		(property "License" "Apache-2.0"
			(at 228.79 -82.99 0)
			(layer "B.Fab")
			(hide yes)
			(effects
				(font
					(size 1 1)
					(thickness 0.15)
				)
				(justify mirror)
			)
		)
		(property "MPN" "CR0402-FX-1002GLF"
			(at 228.79 -82.99 0)
			(layer "B.Fab")
			(hide yes)
			(effects
				(font
					(size 1 1)
					(thickness 0.15)
				)
				(justify mirror)
			)
		)
		(property "Manufacturer" "Bourns"
			(at 228.79 -82.99 0)
			(layer "B.Fab")
			(hide yes)
			(effects
				(font
					(size 1 1)
					(thickness 0.15)
				)
				(justify mirror)
			)
		)
		(property "Tolerance" "1%"
			(at 228.79 -82.99 0)
			(layer "B.Fab")
			(hide yes)
			(effects
				(font
					(size 1 1)
					(thickness 0.15)
				)
				(justify mirror)
			)
		)
		(property "Val" "10k"
			(at 228.79 -82.99 0)
			(layer "B.Fab")
			(hide yes)
			(effects
				(font
					(size 1 1)
					(thickness 0.15)
				)
				(justify mirror)
			)
		)
		(sheetname "/Power Supply/")
		(sheetfile "supply.kicad_sch")
		(attr smd)
		(fp_rect
			(start -0.925 0.47)
			(end 0.925 -0.47)
			(stroke
				(width 0.05)
				(type default)
			)
			(fill no)
			(layer "B.CrtYd")
		)
		(fp_rect
			(start -0.5 0.25)
			(end 0.5 -0.25)
			(stroke
				(width 0.15)
				(type solid)
			)
			(fill no)
			(layer "B.Fab")
		)
		(fp_text user "Author: Antmicro"
			(at -0.95 -4.169 270)
			(layer "B.Fab")
			(effects
				(font
					(size 0.7 0.7)
					(thickness 0.15)
				)
				(justify left bottom mirror)
			)
		)
		(fp_text user "License: Apache-2.0"
			(at -0.95 -5.169 270)
			(layer "B.Fab")
			(effects
				(font
					(size 0.7 0.7)
					(thickness 0.15)
				)
				(justify left bottom mirror)
			)
		)
		(fp_text user "${REFERENCE}"
			(at -0.95 -3.168 270)
			(layer "B.Fab")
			(effects
				(font
					(size 0.7 0.7)
					(thickness 0.15)
				)
				(justify left bottom mirror)
			)
		)
		(pad "1" smd roundrect
			(at -0.48 0 90)
			(size 0.59 0.64)
			(layers "B.Cu" "B.Mask" "B.Paste")
			(roundrect_rratio 0.25)
			(net 1 "GND")
			(pintype "passive")
		)
		(pad "2" smd roundrect
			(at 0.48 0 90)
			(size 0.59 0.64)
			(layers "B.Cu" "B.Mask" "B.Paste")
			(roundrect_rratio 0.25)
			(net 349 "Net-(U4-ILIM)")
			(pintype "passive")
		)
	)
)
